# T6G (Grand Teton) — schematic netlist excerpt (pin names and nets, part order shuffled) for the footprints in the layout excerpt that follows; sources: Cadence DE-HDL packaged netlist, KiCad conversion of 04192023_DAF0TMB3IC0_F0TG_MB_C_brd_V02_OCP.brd

PU13  ISL99390FRZTR5935  ISL99390FRZ-TR5935 IC  pkg QFN21_6X5XB  page 201
  VOS  = PVDDCR_CPU1_P0_VOS1
  AGND  = GND
  VCC  = PVDDCR_CPU1_P0_VCC1
  PVCC  = PVDDCR_CPU1_P0_PVCC
  PGND1  = GND
  GL1  = NC_PVDDCR_CPU1_P0_GL1_1
  PGND2  = GND
  SW  = SW_PVDDCR_CPU1_P0_SW1
  VIN1  = SW_P12V_AUX_PVDDCR_CPU1_P0_FLT
  VIN2  = SW_P12V_AUX_PVDDCR_CPU1_P0_FLT
  DNC  = NC_PVDDCR_CPU1_P0_DNC1
  PHASE  = SW_PVDDCR_CPU1_P0_BOOTR1
  BOOT  = SW_PVDDCR_CPU1_P0_BOOT1
  PWM  = PVDDCR_CPU1_P0_PWM1
  EN  = PVDDCR_CPU1_P0_VCC1
  TOUT_FLT  = PVDDCR_CPU1_P0_TEMP0
  LSET  = PVDDCR_CPU1_P0_LSET1
  IOUT  = PVDDCR_CPU1_P0_IMON1
  REFIN  = PVDDCR_CPU1_P0_VCCS
  PGND3  = GND
  GL2  = NC_PVDDCR_CPU1_P0_GL2_1

(kicad_pcb
	(version 20260206)
	(generator "pcbnew")
	(generator_version "10.0")
	(general
		(thickness 1.6)
		(legacy_teardrops no)
	)
	(paper "A4")
	(title_block
		(title "04192023_DAF0TMB3IC0_F0TG_MB_C_brd_V02_OCP.brd")
		(comment 1 "Grand Teton / footprints 3548-3548 of 8354")
	)
	(layers
		(0 "F.Cu" signal "TOP")
		(4 "In1.Cu" signal "GND")
		(6 "In2.Cu" signal "IN1")
		(8 "In3.Cu" signal "GND1")
		(10 "In4.Cu" signal "IN2")
		(12 "In5.Cu" signal "GND2")
		(14 "In6.Cu" signal "IN3")
		(16 "In7.Cu" signal "GND3")
		(18 "In8.Cu" signal "VCC")
		(20 "In9.Cu" signal "VCC1")
		(22 "In10.Cu" signal "GND4")
		(24 "In11.Cu" signal "IN4")
		(26 "In12.Cu" signal "GND5")
		(28 "In13.Cu" signal "IN5")
		(30 "In14.Cu" signal "GND6")
		(32 "In15.Cu" signal "IN6")
		(34 "In16.Cu" signal "GND7")
		(2 "B.Cu" signal "BOTTOM")
		(9 "F.Adhes" user "F.Adhesive")
		(11 "B.Adhes" user "B.Adhesive")
		(13 "F.Paste" user "Package Geometry/Pastemask Top")
		(15 "B.Paste" user "Package Geometry/Pastemask Bottom")
		(5 "F.SilkS" user "Ref Des/Silkscreen Top")
		(7 "B.SilkS" user "Ref Des/Silkscreen Bottom")
		(1 "F.Mask" user "Board Geometry/Soldermask Top")
		(3 "B.Mask" user "Board Geometry/Soldermask Bottom")
		(17 "Dwgs.User" user "User.Drawings")
		(19 "Cmts.User" user "User.Comments")
		(21 "Eco1.User" user "User.Eco1")
		(23 "Eco2.User" user "User.Eco2")
		(25 "Edge.Cuts" user "Board Geometry/Outline")
		(27 "Margin" user)
		(31 "F.CrtYd" user "Package Geometry/Place Bound Top")
		(29 "B.CrtYd" user "Package Geometry/Place Bound Bottom")
		(35 "F.Fab" user "Ref Des/Assembly Top")
		(33 "B.Fab" user "Ref Des/Assembly Bottom")
	)
	(footprint ""
		(layer "F.Cu")
		(at 335.05902 -334.973676)
		(property "Reference" "PU13"
			(at -2.95402 -7.772654 0)
			(unlocked yes)
			(layer "F.SilkS")
			(effects
				(font
					(size 0.7874 0.5842)
					(thickness 0.1524)
				)
				(justify left)
			)
		)
		(property "Value" ""
			(at 0 0 0)
			(layer "F.Fab")
			(effects
				(font
					(size 1.27 1.27)
				)
			)
		)
		(duplicate_pad_numbers_are_jumpers no)
		(fp_line
			(start -2.500122 -2.999994)
			(end -2.24409 -2.999994)
			(stroke
				(width 0.1524)
				(type default)
			)
			(layer "F.SilkS")
		)
		(fp_line
			(start -2.500122 -2.529078)
			(end -2.500122 -2.999994)
			(stroke
				(width 0.1524)
				(type default)
			)
			(layer "F.SilkS")
		)
		(fp_line
			(start -2.500122 0.6604)
			(end -2.500122 0.229108)
			(stroke
				(width 0.1524)
				(type default)
			)
			(layer "F.SilkS")
		)
		(fp_line
			(start -2.500122 2.999994)
			(end -2.500122 2.339594)
			(stroke
				(width 0.1524)
				(type default)
			)
			(layer "F.SilkS")
		)
		(fp_line
			(start -2.2987 2.999994)
			(end -2.500122 2.999994)
			(stroke
				(width 0.1524)
				(type default)
			)
			(layer "F.SilkS")
		)
		(fp_line
			(start 2.31394 -2.999994)
			(end 2.500122 -2.999994)
			(stroke
				(width 0.1524)
				(type default)
			)
			(layer "F.SilkS")
		)
		(fp_line
			(start 2.500122 -2.999994)
			(end 2.500122 -2.44348)
			(stroke
				(width 0.1524)
				(type default)
			)
			(layer "F.SilkS")
		)
		(fp_line
			(start 2.500122 2.339594)
			(end 2.500122 2.999994)
			(stroke
				(width 0.1524)
				(type default)
			)
			(layer "F.SilkS")
		)
		(fp_line
			(start 2.500122 2.999994)
			(end 2.2987 2.999994)
			(stroke
				(width 0.1524)
				(type default)
			)
			(layer "F.SilkS")
		)
		(fp_poly
			(pts
				(xy -2.77114 -2.42824) (xy -3.444748 -2.652776) (xy -2.995676 -3.101848)
			)
			(stroke
				(width 0)
				(type default)
			)
			(fill yes)
			(layer "F.SilkS")
		)
		(fp_line
			(start -2.500122 -2.999994)
			(end 2.500122 -2.999994)
			(stroke
				(width 0.1)
				(type default)
			)
			(layer "F.Fab")
		)
		(fp_line
			(start -2.500122 2.999994)
			(end -2.500122 -2.999994)
			(stroke
				(width 0.1)
				(type default)
			)
			(layer "F.Fab")
		)
		(fp_line
			(start 2.500122 -2.999994)
			(end 2.500122 2.999994)
			(stroke
				(width 0.1)
				(type default)
			)
			(layer "F.Fab")
		)
		(fp_line
			(start 2.500122 2.999994)
			(end -2.500122 2.999994)
			(stroke
				(width 0.1)
				(type default)
			)
			(layer "F.Fab")
		)
		(fp_poly
			(pts
				(xy -4.218432 -2.783078) (xy -4.218432 -1.767078) (xy -3.202432 -2.275078)
			)
			(stroke
				(width 0)
				(type default)
			)
			(fill yes)
			(layer "F.Fab")
		)
		(pad "1" smd rect
			(at -2.400046 -2.275078 90)
			(size 0.2286 0.6096)
			(layers "F.Cu" "F.Mask" "F.Paste")
			(net "PVDDCR_CPU1_P0_VOS1")
		)
		(pad "2" smd rect
			(at -2.400046 -1.82499 90)
			(size 0.2286 0.6096)
			(layers "F.Cu" "F.Mask" "F.Paste")
			(net "GND")
		)
		(pad "3" smd rect
			(at -2.400046 -1.374902 90)
			(size 0.2286 0.6096)
			(layers "F.Cu" "F.Mask" "F.Paste")
			(net "PVDDCR_CPU1_P0_VCC1")
		)
		(pad "4" smd rect
			(at -2.400046 -0.925068 90)
			(size 0.2286 0.6096)
			(layers "F.Cu" "F.Mask" "F.Paste")
			(net "PVDDCR_CPU1_P0_PVCC")
		)
		(pad "5" smd rect
			(at -2.400046 -0.47498 90)
			(size 0.2286 0.6096)
			(layers "F.Cu" "F.Mask" "F.Paste")
			(net "GND")
		)
		(pad "6" smd rect
			(at -2.400046 -0.024892 90)
			(size 0.2286 0.6096)
			(layers "F.Cu" "F.Mask" "F.Paste")
			(net "NC_PVDDCR_CPU1_P0_GL1_1")
		)
		(pad "7_9-20_24" smd circle
			(at 0 1.150112 90)
			(size 0 0)
			(layers "F.Cu" "F.Mask" "F.Paste")
			(net "GND")
		)
		(pad "10_19" smd rect
			(at 0 2.899918 90)
			(size 0.6096 4.318)
			(layers "F.Cu" "F.Mask" "F.Paste")
			(net "SW_PVDDCR_CPU1_P0_SW1")
		)
		(pad "25_29" smd rect
			(at 1.549908 -1.279906 270)
			(size 2.0574 2.3114)
			(layers "F.Cu" "F.Mask" "F.Paste")
			(net "SW_P12V_AUX_PVDDCR_CPU1_P0_FLT")
		)
		(pad "30" smd rect
			(at 2.05994 -2.899918)
			(size 0.2286 0.6096)
			(layers "F.Cu" "F.Mask" "F.Paste")
			(net "SW_P12V_AUX_PVDDCR_CPU1_P0_FLT")
		)
		(pad "31" smd rect
			(at 1.610106 -2.899918)
			(size 0.2286 0.6096)
			(layers "F.Cu" "F.Mask" "F.Paste")
			(net "NC_PVDDCR_CPU1_P0_DNC1")
		)
		(pad "32" smd rect
			(at 1.160018 -2.899918)
			(size 0.2286 0.6096)
			(layers "F.Cu" "F.Mask" "F.Paste")
			(net "SW_PVDDCR_CPU1_P0_BOOTR1")
		)
		(pad "33" smd rect
			(at 0.70993 -2.899918)
			(size 0.2286 0.6096)
			(layers "F.Cu" "F.Mask" "F.Paste")
			(net "SW_PVDDCR_CPU1_P0_BOOT1")
		)
		(pad "34" smd rect
			(at 0.260096 -2.899918)
			(size 0.2286 0.6096)
			(layers "F.Cu" "F.Mask" "F.Paste")
			(net "PVDDCR_CPU1_P0_PWM1")
		)
		(pad "35" smd rect
			(at -0.189992 -2.899918)
			(size 0.2286 0.6096)
			(layers "F.Cu" "F.Mask" "F.Paste")
			(net "PVDDCR_CPU1_P0_VCC1")
		)
		(pad "36" smd rect
			(at -0.64008 -2.899918)
			(size 0.2286 0.6096)
			(layers "F.Cu" "F.Mask" "F.Paste")
			(net "PVDDCR_CPU1_P0_TEMP0")
		)
		(pad "37" smd rect
			(at -1.089914 -2.899918)
			(size 0.2286 0.6096)
			(layers "F.Cu" "F.Mask" "F.Paste")
			(net "PVDDCR_CPU1_P0_LSET1")
		)
		(pad "38" smd rect
			(at -1.540002 -2.899918)
			(size 0.2286 0.6096)
			(layers "F.Cu" "F.Mask" "F.Paste")
			(net "PVDDCR_CPU1_P0_IMON1")
		)
		(pad "39" smd rect
			(at -1.99009 -2.899918)
			(size 0.2286 0.6096)
			(layers "F.Cu" "F.Mask" "F.Paste")
			(net "PVDDCR_CPU1_P0_VCCS")
		)
		(pad "40" smd rect
			(at -0.87503 -1.27508)
			(size 1.7526 1.9558)
			(layers "F.Cu" "F.Mask" "F.Paste")
			(net "GND")
		)
		(pad "41" smd rect
			(at -1.525016 0.249936 270)
			(size 0.3048 0.4572)
			(layers "F.Cu" "F.Mask" "F.Paste")
			(net "NC_PVDDCR_CPU1_P0_GL2_1")
		)
		(zone
			(layer "F.Cu")
			(hatch none 0.5)
			(connect_pads
				(clearance 0)
			)
			(min_thickness 0.25)
			(keepout
				(tracks not_allowed)
				(vias allowed)
				(pads allowed)
				(copperpour not_allowed)
				(footprints allowed)
			)
			(placement
				(enabled no)
				(sheetname "")
			)
			(fill
				(thermal_gap 0.5)
				(thermal_bridge_width 0.5)
				(island_removal_mode 0)
			)
			(polygon
				(pts
					(xy 332.558898 -332.3971) (xy 332.558898 -332.722982) (xy 337.559142 -332.722982) (xy 337.559142 -332.41234)
					(xy 337.26882 -332.41234) (xy 337.26882 -332.429358) (xy 332.84922 -332.429358) (xy 332.84922 -332.3971)
				)
			)
		)
		(zone
			(layer "F.Cu")
			(hatch none 0.5)
			(connect_pads
				(clearance 0)
			)
			(min_thickness 0.25)
			(keepout
				(tracks not_allowed)
				(vias allowed)
				(pads allowed)
				(copperpour not_allowed)
				(footprints allowed)
			)
			(placement
				(enabled no)
				(sheetname "")
			)
			(fill
				(thermal_gap 0.5)
				(thermal_bridge_width 0.5)
				(island_removal_mode 0)
			)
			(polygon
				(pts
					(xy 335.11109 -335.220056) (xy 335.11109 -337.277456) (xy 333.25689 -337.277456) (xy 333.25689 -337.03641)
					(xy 333.014574 -337.03641) (xy 333.014574 -337.517994) (xy 336.841846 -337.517994) (xy 336.841846 -337.333082)
					(xy 335.402428 -337.333082) (xy 335.402428 -335.174082) (xy 337.559142 -335.174082) (xy 337.559142 -334.9244)
					(xy 335.406746 -334.9244)
				)
			)
		)
	)
)
